(kicad_pcb
	(version 20260206)
	(generator "pcbnew")
	(generator_version "10.0")
	(general
		(thickness 1.6)
		(legacy_teardrops no)
	)
	(paper "A4")
	(title_block
		(title "04192023_DAF0TMB3IC0_F0TG_MB_C_brd_V02_OCP.brd")
		(comment 1 "Grand Teton / footprint 4641 of 8354 (U6012), pads 337-354 of 354")
	)
	(layers
		(0 "F.Cu" signal "TOP")
		(4 "In1.Cu" signal "GND")
		(6 "In2.Cu" signal "IN1")
		(8 "In3.Cu" signal "GND1")
		(10 "In4.Cu" signal "IN2")
		(12 "In5.Cu" signal "GND2")
		(14 "In6.Cu" signal "IN3")
		(16 "In7.Cu" signal "GND3")
		(18 "In8.Cu" signal "VCC")
		(20 "In9.Cu" signal "VCC1")
		(22 "In10.Cu" signal "GND4")
		(24 "In11.Cu" signal "IN4")
		(26 "In12.Cu" signal "GND5")
		(28 "In13.Cu" signal "IN5")
		(30 "In14.Cu" signal "GND6")
		(32 "In15.Cu" signal "IN6")
		(34 "In16.Cu" signal "GND7")
		(2 "B.Cu" signal "BOTTOM")
		(9 "F.Adhes" user "F.Adhesive")
		(11 "B.Adhes" user "B.Adhesive")
		(13 "F.Paste" user "Package Geometry/Pastemask Top")
		(15 "B.Paste" user "Package Geometry/Pastemask Bottom")
		(5 "F.SilkS" user "Ref Des/Silkscreen Top")
		(7 "B.SilkS" user "Ref Des/Silkscreen Bottom")
		(1 "F.Mask" user "Board Geometry/Soldermask Top")
		(3 "B.Mask" user "Board Geometry/Soldermask Bottom")
		(17 "Dwgs.User" user "User.Drawings")
		(19 "Cmts.User" user "User.Comments")
		(21 "Eco1.User" user "User.Eco1")
		(23 "Eco2.User" user "User.Eco2")
		(25 "Edge.Cuts" user "Board Geometry/Outline")
		(27 "Margin" user)
		(31 "F.CrtYd" user "Package Geometry/Place Bound Top")
		(29 "B.CrtYd" user "Package Geometry/Place Bound Bottom")
		(35 "F.Fab" user "Ref Des/Assembly Top")
		(33 "B.Fab" user "Ref Des/Assembly Bottom")
	)
	(footprint ""
		(layer "F.Cu")
		(at 412.095696 -395.724634)
		(property "Reference" "U6012"
			(at -8.00862 -7.649972 0)
			(unlocked yes)
			(layer "F.SilkS")
			(effects
				(font
					(size 0.7874 0.5842)
					(thickness 0.1524)
				)
				(justify left)
			)
		)
		(property "Value" ""
			(at 0 0 0)
			(layer "F.Fab")
			(effects
				(font
					(size 1.27 1.27)
				)
			)
		)
		(duplicate_pad_numbers_are_jumpers no)
		(pad "P10" smd circle
			(at 8.802624 -1.431798)
			(size 0.381 0.381)
			(layers "F.Cu" "F.Mask" "F.Paste")
			(net "P5E_CPU0_P2_TX_BUF_DN<15>")
		)
		(pad "P29" smd circle
			(at 8.802624 2.032254)
			(size 0.381 0.381)
			(layers "F.Cu" "F.Mask" "F.Paste")
			(net "P5E_CPU0_P2_RX_DN<15>")
		)
		(pad "R1" smd oval
			(at 8.64997 -3.938524)
			(size 0.254 0.3302)
			(layers "F.Cu" "F.Mask" "F.Paste")
			(net "P5E_CPU0_P2_RX_BUF_DP<15>")
		)
		(pad "R35" smd oval
			(at 8.64997 3.940048)
			(size 0.254 0.3302)
			(layers "F.Cu" "F.Mask" "F.Paste")
			(net "P5E_CPU0_P2_TX_C_DP<15>")
		)
		(pad "T4" smd circle
			(at 8.402574 -2.817368)
			(size 0.381 0.381)
			(layers "F.Cu" "F.Mask" "F.Paste")
			(net "GND")
		)
		(pad "T13" smd circle
			(at 8.402574 -0.79629)
			(size 0.3048 0.3048)
			(layers "F.Cu" "F.Mask" "F.Paste")
			(net "GND")
		)
		(pad "T17" smd circle
			(at 8.402574 -0.296164)
			(size 0.3048 0.3048)
			(layers "F.Cu" "F.Mask" "F.Paste")
			(net "P0V9_CPU0_RT2_2A")
		)
		(pad "T20" smd circle
			(at 8.402574 0.203708)
			(size 0.3048 0.3048)
			(layers "F.Cu" "F.Mask" "F.Paste")
			(net "P0V9_CPU0_RT2_2A")
		)
		(pad "T22" smd circle
			(at 8.402574 0.703834)
			(size 0.3048 0.3048)
			(layers "F.Cu" "F.Mask" "F.Paste")
			(net "GND")
		)
		(pad "T32" smd circle
			(at 8.402574 2.724912)
			(size 0.381 0.381)
			(layers "F.Cu" "F.Mask" "F.Paste")
			(net "GND")
		)
		(pad "U2" smd circle
			(at 8.349996 -3.41884)
			(size 0.3048 0.3048)
			(layers "F.Cu" "F.Mask" "F.Paste")
			(net "GND")
		)
		(pad "U34" smd circle
			(at 8.349996 3.420364)
			(size 0.3048 0.3048)
			(layers "F.Cu" "F.Mask" "F.Paste")
			(net "GND")
		)
		(pad "V1" smd oval
			(at 8.050022 -3.938524)
			(size 0.254 0.3302)
			(layers "F.Cu" "F.Mask" "F.Paste")
			(net "GND")
		)
		(pad "V35" smd oval
			(at 8.050022 3.940048)
			(size 0.254 0.3302)
			(layers "F.Cu" "F.Mask" "F.Paste")
			(net "GND")
		)
		(pad "W7" smd circle
			(at 8.002524 -2.12471)
			(size 0.381 0.381)
			(layers "F.Cu" "F.Mask" "F.Paste")
			(net "P5E_CPU0_P2_TX_BUF_DP<14>")
		)
		(pad "W26" smd circle
			(at 8.002524 1.339342)
			(size 0.381 0.381)
			(layers "F.Cu" "F.Mask" "F.Paste")
			(net "P5E_CPU0_P2_RX_DP<14>")
		)
		(pad "Y2" smd circle
			(at 7.750048 -3.41884)
			(size 0.3048 0.3048)
			(layers "F.Cu" "F.Mask" "F.Paste")
			(net "P5E_CPU0_P2_RX_BUF_DN<14>")
		)
		(pad "Y34" smd circle
			(at 7.750048 3.420364)
			(size 0.3048 0.3048)
			(layers "F.Cu" "F.Mask" "F.Paste")
			(net "P5E_CPU0_P2_TX_C_DN<14>")
		)
	)
)
